(kicad_pcb
	(version 20260206)
	(generator "pcbnew")
	(generator_version "10.0")
	(general
		(thickness 1.6)
		(legacy_teardrops no)
	)
	(paper "A4")
	(title_block
		(title "03242023_DA0F0TMBIJ0_F0T_Motherboard_J_brd_V01_OCP.brd")
		(comment 1 "Grand Teton / footprints 3189-3195 of 6105")
	)
	(layers
		(0 "F.Cu" signal "TOP")
		(4 "In1.Cu" signal "GND")
		(6 "In2.Cu" signal "IN1")
		(8 "In3.Cu" signal "GND1")
		(10 "In4.Cu" signal "IN2")
		(12 "In5.Cu" signal "GND2")
		(14 "In6.Cu" signal "IN3")
		(16 "In7.Cu" signal "GND3")
		(18 "In8.Cu" signal "VCC")
		(20 "In9.Cu" signal "VCC1")
		(22 "In10.Cu" signal "GND4")
		(24 "In11.Cu" signal "IN4")
		(26 "In12.Cu" signal "GND5")
		(28 "In13.Cu" signal "IN5")
		(30 "In14.Cu" signal "GND6")
		(32 "In15.Cu" signal "IN6")
		(34 "In16.Cu" signal "GND7")
		(2 "B.Cu" signal "BOTTOM")
		(9 "F.Adhes" user "F.Adhesive")
		(11 "B.Adhes" user "B.Adhesive")
		(13 "F.Paste" user "Package Geometry/Pastemask Top")
		(15 "B.Paste" user "Package Geometry/Pastemask Bottom")
		(5 "F.SilkS" user "Ref Des/Silkscreen Top")
		(7 "B.SilkS" user "Ref Des/Silkscreen Bottom")
		(1 "F.Mask" user "Board Geometry/Soldermask Top")
		(3 "B.Mask" user "Board Geometry/Soldermask Bottom")
		(17 "Dwgs.User" user "User.Drawings")
		(19 "Cmts.User" user "User.Comments")
		(21 "Eco1.User" user "User.Eco1")
		(23 "Eco2.User" user "User.Eco2")
		(25 "Edge.Cuts" user "Board Geometry/Outline")
		(27 "Margin" user)
		(31 "F.CrtYd" user "Package Geometry/Place Bound Top")
		(29 "B.CrtYd" user "Package Geometry/Place Bound Bottom")
		(35 "F.Fab" user "Ref Des/Assembly Top")
		(33 "B.Fab" user "Ref Des/Assembly Bottom")
	)
	(footprint ""
		(layer "F.Cu")
		(at 362.1405 -409.654248 180)
		(property "Reference" "R4549"
			(at 0 0 180)
			(layer "F.SilkS")
			(hide yes)
			(effects
				(font
					(size 1.27 1.27)
				)
			)
		)
		(property "Value" ""
			(at 0 0 180)
			(layer "F.Fab")
			(effects
				(font
					(size 1.27 1.27)
				)
			)
		)
		(duplicate_pad_numbers_are_jumpers no)
		(fp_line
			(start 0.7874 0.4064)
			(end -0.7874 0.4064)
			(stroke
				(width 0.1524)
				(type default)
			)
			(layer "F.SilkS")
		)
		(fp_line
			(start 0.7874 -0.4064)
			(end 0.7874 0.4064)
			(stroke
				(width 0.1524)
				(type default)
			)
			(layer "F.SilkS")
		)
		(fp_line
			(start -0.7874 0.4064)
			(end -0.7874 -0.4064)
			(stroke
				(width 0.1524)
				(type default)
			)
			(layer "F.SilkS")
		)
		(fp_line
			(start -0.7874 -0.4064)
			(end 0.7874 -0.4064)
			(stroke
				(width 0.1524)
				(type default)
			)
			(layer "F.SilkS")
		)
		(fp_line
			(start 0.67945 0.3048)
			(end 0.120396 0.3048)
			(stroke
				(width 0.1)
				(type default)
			)
			(layer "F.Fab")
		)
		(fp_line
			(start 0.67945 -0.3048)
			(end 0.67945 0.3048)
			(stroke
				(width 0.1)
				(type default)
			)
			(layer "F.Fab")
		)
		(fp_line
			(start 0.12065 -0.2794)
			(end 0.12065 -0.3048)
			(stroke
				(width 0.1)
				(type default)
			)
			(layer "F.Fab")
		)
		(fp_line
			(start 0.12065 -0.3048)
			(end 0.67945 -0.3048)
			(stroke
				(width 0.1)
				(type default)
			)
			(layer "F.Fab")
		)
		(fp_line
			(start 0.120396 0.3048)
			(end 0.120396 0.2794)
			(stroke
				(width 0.1)
				(type default)
			)
			(layer "F.Fab")
		)
		(fp_line
			(start 0.120396 0.2794)
			(end -0.12065 0.2794)
			(stroke
				(width 0.1)
				(type default)
			)
			(layer "F.Fab")
		)
		(fp_line
			(start -0.12065 0.3048)
			(end -0.67945 0.3048)
			(stroke
				(width 0.1)
				(type default)
			)
			(layer "F.Fab")
		)
		(fp_line
			(start -0.12065 0.2794)
			(end -0.12065 0.3048)
			(stroke
				(width 0.1)
				(type default)
			)
			(layer "F.Fab")
		)
		(fp_line
			(start -0.12065 -0.2794)
			(end 0.12065 -0.2794)
			(stroke
				(width 0.1)
				(type default)
			)
			(layer "F.Fab")
		)
		(fp_line
			(start -0.12065 -0.305054)
			(end -0.12065 -0.2794)
			(stroke
				(width 0.1)
				(type default)
			)
			(layer "F.Fab")
		)
		(fp_line
			(start -0.67945 0.3048)
			(end -0.67945 -0.305054)
			(stroke
				(width 0.1)
				(type default)
			)
			(layer "F.Fab")
		)
		(fp_line
			(start -0.67945 -0.305054)
			(end -0.12065 -0.305054)
			(stroke
				(width 0.1)
				(type default)
			)
			(layer "F.Fab")
		)
		(pad "1" smd circle
			(at -0.40005 0 180)
			(size 0 0)
			(layers "F.Cu" "F.Mask" "F.Paste")
			(net "P3V3_AUX")
		)
		(pad "2" smd circle
			(at 0.40005 0 180)
			(size 0 0)
			(layers "F.Cu" "F.Mask" "F.Paste")
			(net "SWB_HSC_EN_BUF_R")
		)
	)
	(footprint ""
		(layer "F.Cu")
		(at 429.471836 -16.088614 90)
		(property "Reference" "C867"
			(at 0 0 90)
			(layer "F.SilkS")
			(hide yes)
			(effects
				(font
					(size 1.27 1.27)
				)
			)
		)
		(property "Value" ""
			(at 0 0 90)
			(layer "F.Fab")
			(effects
				(font
					(size 1.27 1.27)
				)
			)
		)
		(duplicate_pad_numbers_are_jumpers no)
		(fp_line
			(start 0.299974 -0.150114)
			(end 0.299974 0.150114)
			(stroke
				(width 0.1)
				(type default)
			)
			(layer "F.Fab")
		)
		(fp_line
			(start -0.299974 -0.150114)
			(end 0.299974 -0.150114)
			(stroke
				(width 0.1)
				(type default)
			)
			(layer "F.Fab")
		)
		(fp_line
			(start 0.299974 0.150114)
			(end -0.299974 0.150114)
			(stroke
				(width 0.1)
				(type default)
			)
			(layer "F.Fab")
		)
		(fp_line
			(start -0.299974 0.150114)
			(end -0.299974 -0.150114)
			(stroke
				(width 0.1)
				(type default)
			)
			(layer "F.Fab")
		)
		(pad "1" smd rect
			(at -0.2667 0 90)
			(size 0.3048 0.381)
			(layers "F.Cu" "F.Mask" "F.Paste")
			(net "P5E_CPU0_PE1_TX_C_DP<1>")
		)
		(pad "2" smd rect
			(at 0.2667 0 90)
			(size 0.3048 0.381)
			(layers "F.Cu" "F.Mask" "F.Paste")
			(net "P5E_CPU0_PE1_TX_DP<1>")
		)
	)
	(footprint ""
		(layer "F.Cu")
		(at 459.267814 -381.606552 179.946)
		(property "Reference" "PR91"
			(at 0 0 179.946)
			(layer "F.SilkS")
			(hide yes)
			(effects
				(font
					(size 1.27 1.27)
				)
			)
		)
		(property "Value" ""
			(at 0 0 179.946)
			(layer "F.Fab")
			(effects
				(font
					(size 1.27 1.27)
				)
			)
		)
		(duplicate_pad_numbers_are_jumpers no)
		(fp_line
			(start 0.787525 -0.40638)
			(end 0.787275 0.40642)
			(stroke
				(width 0.1524)
				(type default)
			)
			(layer "F.SilkS")
		)
		(fp_line
			(start 0.787275 0.40642)
			(end -0.787525 0.40638)
			(stroke
				(width 0.1524)
				(type default)
			)
			(layer "F.SilkS")
		)
		(fp_line
			(start -0.787275 -0.40642)
			(end 0.787525 -0.40638)
			(stroke
				(width 0.1524)
				(type default)
			)
			(layer "F.SilkS")
		)
		(fp_line
			(start -0.787525 0.40638)
			(end -0.787275 -0.40642)
			(stroke
				(width 0.1524)
				(type default)
			)
			(layer "F.SilkS")
		)
		(fp_line
			(start 0.679417 -0.304678)
			(end 0.679484 0.304922)
			(stroke
				(width 0.1)
				(type default)
			)
			(layer "F.Fab")
		)
		(fp_line
			(start 0.679484 0.304922)
			(end 0.120429 0.304687)
			(stroke
				(width 0.1)
				(type default)
			)
			(layer "F.Fab")
		)
		(fp_line
			(start 0.120641 -0.279514)
			(end 0.120617 -0.304914)
			(stroke
				(width 0.1)
				(type default)
			)
			(layer "F.Fab")
		)
		(fp_line
			(start 0.120617 -0.304914)
			(end 0.679417 -0.304678)
			(stroke
				(width 0.1)
				(type default)
			)
			(layer "F.Fab")
		)
		(fp_line
			(start 0.120429 0.304687)
			(end 0.120405 0.279287)
			(stroke
				(width 0.1)
				(type default)
			)
			(layer "F.Fab")
		)
		(fp_line
			(start 0.120405 0.279287)
			(end -0.120641 0.279514)
			(stroke
				(width 0.1)
				(type default)
			)
			(layer "F.Fab")
		)
		(fp_line
			(start -0.120659 -0.279286)
			(end 0.120641 -0.279514)
			(stroke
				(width 0.1)
				(type default)
			)
			(layer "F.Fab")
		)
		(fp_line
			(start -0.120683 -0.30494)
			(end -0.120659 -0.279286)
			(stroke
				(width 0.1)
				(type default)
			)
			(layer "F.Fab")
		)
		(fp_line
			(start -0.120617 0.304914)
			(end -0.679417 0.304678)
			(stroke
				(width 0.1)
				(type default)
			)
			(layer "F.Fab")
		)
		(fp_line
			(start -0.120641 0.279514)
			(end -0.120617 0.304914)
			(stroke
				(width 0.1)
				(type default)
			)
			(layer "F.Fab")
		)
		(fp_line
			(start -0.679484 -0.305176)
			(end -0.120683 -0.30494)
			(stroke
				(width 0.1)
				(type default)
			)
			(layer "F.Fab")
		)
		(fp_line
			(start -0.679417 0.304678)
			(end -0.679484 -0.305176)
			(stroke
				(width 0.1)
				(type default)
			)
			(layer "F.Fab")
		)
		(pad "1" smd circle
			(at -0.40005 0 179.946)
			(size 0 0)
			(layers "F.Cu" "F.Mask" "F.Paste")
			(net "P5V_AUX_FB")
		)
		(pad "2" smd circle
			(at 0.40005 0 179.946)
			(size 0 0)
			(layers "F.Cu" "F.Mask" "F.Paste")
			(net "GND")
		)
	)
	(footprint ""
		(layer "F.Cu")
		(at 368.71402 -402.910548)
		(property "Reference" "R3036"
			(at 0 0 0)
			(layer "F.SilkS")
			(hide yes)
			(effects
				(font
					(size 1.27 1.27)
				)
			)
		)
		(property "Value" ""
			(at 0 0 0)
			(layer "F.Fab")
			(effects
				(font
					(size 1.27 1.27)
				)
			)
		)
		(duplicate_pad_numbers_are_jumpers no)
		(fp_line
			(start -0.7874 -0.4064)
			(end 0.7874 -0.4064)
			(stroke
				(width 0.1524)
				(type default)
			)
			(layer "F.SilkS")
		)
		(fp_line
			(start -0.7874 0.4064)
			(end -0.7874 -0.4064)
			(stroke
				(width 0.1524)
				(type default)
			)
			(layer "F.SilkS")
		)
		(fp_line
			(start 0.7874 -0.4064)
			(end 0.7874 0.4064)
			(stroke
				(width 0.1524)
				(type default)
			)
			(layer "F.SilkS")
		)
		(fp_line
			(start 0.7874 0.4064)
			(end -0.7874 0.4064)
			(stroke
				(width 0.1524)
				(type default)
			)
			(layer "F.SilkS")
		)
		(fp_line
			(start -0.67945 -0.305054)
			(end -0.12065 -0.305054)
			(stroke
				(width 0.1)
				(type default)
			)
			(layer "F.Fab")
		)
		(fp_line
			(start -0.67945 0.3048)
			(end -0.67945 -0.305054)
			(stroke
				(width 0.1)
				(type default)
			)
			(layer "F.Fab")
		)
		(fp_line
			(start -0.12065 -0.305054)
			(end -0.12065 -0.2794)
			(stroke
				(width 0.1)
				(type default)
			)
			(layer "F.Fab")
		)
		(fp_line
			(start -0.12065 -0.2794)
			(end 0.12065 -0.2794)
			(stroke
				(width 0.1)
				(type default)
			)
			(layer "F.Fab")
		)
		(fp_line
			(start -0.12065 0.2794)
			(end -0.12065 0.3048)
			(stroke
				(width 0.1)
				(type default)
			)
			(layer "F.Fab")
		)
		(fp_line
			(start -0.12065 0.3048)
			(end -0.67945 0.3048)
			(stroke
				(width 0.1)
				(type default)
			)
			(layer "F.Fab")
		)
		(fp_line
			(start 0.120396 0.2794)
			(end -0.12065 0.2794)
			(stroke
				(width 0.1)
				(type default)
			)
			(layer "F.Fab")
		)
		(fp_line
			(start 0.120396 0.3048)
			(end 0.120396 0.2794)
			(stroke
				(width 0.1)
				(type default)
			)
			(layer "F.Fab")
		)
		(fp_line
			(start 0.12065 -0.3048)
			(end 0.67945 -0.3048)
			(stroke
				(width 0.1)
				(type default)
			)
			(layer "F.Fab")
		)
		(fp_line
			(start 0.12065 -0.2794)
			(end 0.12065 -0.3048)
			(stroke
				(width 0.1)
				(type default)
			)
			(layer "F.Fab")
		)
		(fp_line
			(start 0.67945 -0.3048)
			(end 0.67945 0.3048)
			(stroke
				(width 0.1)
				(type default)
			)
			(layer "F.Fab")
		)
		(fp_line
			(start 0.67945 0.3048)
			(end 0.120396 0.3048)
			(stroke
				(width 0.1)
				(type default)
			)
			(layer "F.Fab")
		)
		(pad "1" smd circle
			(at -0.40005 0)
			(size 0 0)
			(layers "F.Cu" "F.Mask" "F.Paste")
			(net "UART_BMC_BIC_R_BUF_RX")
		)
		(pad "2" smd circle
			(at 0.40005 0)
			(size 0 0)
			(layers "F.Cu" "F.Mask" "F.Paste")
			(net "UART_BMC_BIC_BUF_RX")
		)
	)
	(footprint ""
		(layer "F.Cu")
		(at 58.393076 -79.078836)
		(property "Reference" "D77"
			(at -31.599886 34.341308 90)
			(unlocked yes)
			(layer "F.SilkS")
			(effects
				(font
					(size 0.635 0.4064)
					(thickness 0.1524)
				)
				(justify left)
			)
		)
		(property "Value" ""
			(at 0 0 0)
			(layer "F.Fab")
			(effects
				(font
					(size 1.27 1.27)
				)
			)
		)
		(duplicate_pad_numbers_are_jumpers no)
		(fp_line
			(start -0.90678 0.4826)
			(end -0.90678 -0.4699)
			(stroke
				(width 0.1524)
				(type default)
			)
			(layer "F.SilkS")
		)
		(fp_line
			(start -0.89408 -0.4826)
			(end 0.90678 -0.4826)
			(stroke
				(width 0.1524)
				(type default)
			)
			(layer "F.SilkS")
		)
		(fp_line
			(start -0.79248 -0.4826)
			(end 1.03378 -0.4826)
			(stroke
				(width 0.1524)
				(type default)
			)
			(layer "F.SilkS")
		)
		(fp_line
			(start -0.64008 -0.4826)
			(end 1.16078 -0.4826)
			(stroke
				(width 0.1524)
				(type default)
			)
			(layer "F.SilkS")
		)
		(fp_line
			(start 0.90678 -0.4826)
			(end 0.90678 0.4826)
			(stroke
				(width 0.1524)
				(type default)
			)
			(layer "F.SilkS")
		)
		(fp_line
			(start 0.90678 0.4826)
			(end -0.90678 0.4826)
			(stroke
				(width 0.1524)
				(type default)
			)
			(layer "F.SilkS")
		)
		(fp_line
			(start 1.03378 -0.4826)
			(end 1.03378 0.4826)
			(stroke
				(width 0.1524)
				(type default)
			)
			(layer "F.SilkS")
		)
		(fp_line
			(start 1.03378 0.4826)
			(end -0.79248 0.4826)
			(stroke
				(width 0.1524)
				(type default)
			)
			(layer "F.SilkS")
		)
		(fp_line
			(start 1.16078 -0.4826)
			(end 1.16078 0.4826)
			(stroke
				(width 0.1524)
				(type default)
			)
			(layer "F.SilkS")
		)
		(fp_line
			(start 1.16078 0.4826)
			(end -0.64008 0.4826)
			(stroke
				(width 0.1524)
				(type default)
			)
			(layer "F.SilkS")
		)
		(fp_line
			(start -0.499872 -0.249936)
			(end 0.499872 -0.249936)
			(stroke
				(width 0.1)
				(type default)
			)
			(layer "F.Fab")
		)
		(fp_line
			(start -0.499872 0.249936)
			(end -0.499872 -0.249936)
			(stroke
				(width 0.1)
				(type default)
			)
			(layer "F.Fab")
		)
		(fp_line
			(start 0.499872 -0.249936)
			(end 0.499872 0.249936)
			(stroke
				(width 0.1)
				(type default)
			)
			(layer "F.Fab")
		)
		(fp_line
			(start 0.499872 0.249936)
			(end -0.499872 0.249936)
			(stroke
				(width 0.1)
				(type default)
			)
			(layer "F.Fab")
		)
		(pad "A" smd rect
			(at -0.47498 0)
			(size 0.6096 0.7112)
			(layers "F.Cu" "F.Mask" "F.Paste")
			(net "LED_PWRGD_PVCCINFAON_CPU0")
		)
		(pad "C" smd rect
			(at 0.47498 0)
			(size 0.6096 0.7112)
			(layers "F.Cu" "F.Mask" "F.Paste")
			(net "LED_PWRGD_PVCCINFAON_CPU0_D")
		)
	)
	(footprint ""
		(layer "F.Cu")
		(at 28.578048 -70.83425)
		(property "Reference" "R3142"
			(at 0 0 0)
			(layer "F.SilkS")
			(hide yes)
			(effects
				(font
					(size 1.27 1.27)
				)
			)
		)
		(property "Value" ""
			(at 0 0 0)
			(layer "F.Fab")
			(effects
				(font
					(size 1.27 1.27)
				)
			)
		)
		(duplicate_pad_numbers_are_jumpers no)
		(fp_line
			(start -0.7874 -0.4064)
			(end 0.7874 -0.4064)
			(stroke
				(width 0.1524)
				(type default)
			)
			(layer "F.SilkS")
		)
		(fp_line
			(start -0.7874 0.4064)
			(end -0.7874 -0.4064)
			(stroke
				(width 0.1524)
				(type default)
			)
			(layer "F.SilkS")
		)
		(fp_line
			(start 0.7874 -0.4064)
			(end 0.7874 0.4064)
			(stroke
				(width 0.1524)
				(type default)
			)
			(layer "F.SilkS")
		)
		(fp_line
			(start 0.7874 0.4064)
			(end -0.7874 0.4064)
			(stroke
				(width 0.1524)
				(type default)
			)
			(layer "F.SilkS")
		)
		(fp_line
			(start -0.67945 -0.305054)
			(end -0.12065 -0.305054)
			(stroke
				(width 0.1)
				(type default)
			)
			(layer "F.Fab")
		)
		(fp_line
			(start -0.67945 0.3048)
			(end -0.67945 -0.305054)
			(stroke
				(width 0.1)
				(type default)
			)
			(layer "F.Fab")
		)
		(fp_line
			(start -0.12065 -0.305054)
			(end -0.12065 -0.2794)
			(stroke
				(width 0.1)
				(type default)
			)
			(layer "F.Fab")
		)
		(fp_line
			(start -0.12065 -0.2794)
			(end 0.12065 -0.2794)
			(stroke
				(width 0.1)
				(type default)
			)
			(layer "F.Fab")
		)
		(fp_line
			(start -0.12065 0.2794)
			(end -0.12065 0.3048)
			(stroke
				(width 0.1)
				(type default)
			)
			(layer "F.Fab")
		)
		(fp_line
			(start -0.12065 0.3048)
			(end -0.67945 0.3048)
			(stroke
				(width 0.1)
				(type default)
			)
			(layer "F.Fab")
		)
		(fp_line
			(start 0.120396 0.2794)
			(end -0.12065 0.2794)
			(stroke
				(width 0.1)
				(type default)
			)
			(layer "F.Fab")
		)
		(fp_line
			(start 0.120396 0.3048)
			(end 0.120396 0.2794)
			(stroke
				(width 0.1)
				(type default)
			)
			(layer "F.Fab")
		)
		(fp_line
			(start 0.12065 -0.3048)
			(end 0.67945 -0.3048)
			(stroke
				(width 0.1)
				(type default)
			)
			(layer "F.Fab")
		)
		(fp_line
			(start 0.12065 -0.2794)
			(end 0.12065 -0.3048)
			(stroke
				(width 0.1)
				(type default)
			)
			(layer "F.Fab")
		)
		(fp_line
			(start 0.67945 -0.3048)
			(end 0.67945 0.3048)
			(stroke
				(width 0.1)
				(type default)
			)
			(layer "F.Fab")
		)
		(fp_line
			(start 0.67945 0.3048)
			(end 0.120396 0.3048)
			(stroke
				(width 0.1)
				(type default)
			)
			(layer "F.Fab")
		)
		(pad "1" smd circle
			(at -0.40005 0)
			(size 0 0)
			(layers "F.Cu" "F.Mask" "F.Paste")
			(net "HP_LVC3_OCP_V3_2_PRSNT2_N_R")
		)
		(pad "2" smd circle
			(at 0.40005 0)
			(size 0 0)
			(layers "F.Cu" "F.Mask" "F.Paste")
			(net "HP_LVC3_OCP_V3_2_PRSNT2_N")
		)
	)
	(footprint ""
		(layer "F.Cu")
		(at 317.418212 -62.342268)
		(property "Reference" "R1266"
			(at 0 0 0)
			(layer "F.SilkS")
			(hide yes)
			(effects
				(font
					(size 1.27 1.27)
				)
			)
		)
		(property "Value" ""
			(at 0 0 0)
			(layer "F.Fab")
			(effects
				(font
					(size 1.27 1.27)
				)
			)
		)
		(duplicate_pad_numbers_are_jumpers no)
		(fp_line
			(start -0.7874 -0.4064)
			(end 0.7874 -0.4064)
			(stroke
				(width 0.1524)
				(type default)
			)
			(layer "F.SilkS")
		)
		(fp_line
			(start -0.7874 0.4064)
			(end -0.7874 -0.4064)
			(stroke
				(width 0.1524)
				(type default)
			)
			(layer "F.SilkS")
		)
		(fp_line
			(start 0.7874 -0.4064)
			(end 0.7874 0.4064)
			(stroke
				(width 0.1524)
				(type default)
			)
			(layer "F.SilkS")
		)
		(fp_line
			(start 0.7874 0.4064)
			(end -0.7874 0.4064)
			(stroke
				(width 0.1524)
				(type default)
			)
			(layer "F.SilkS")
		)
		(fp_line
			(start -0.67945 -0.305054)
			(end -0.12065 -0.305054)
			(stroke
				(width 0.1)
				(type default)
			)
			(layer "F.Fab")
		)
		(fp_line
			(start -0.67945 0.3048)
			(end -0.67945 -0.305054)
			(stroke
				(width 0.1)
				(type default)
			)
			(layer "F.Fab")
		)
		(fp_line
			(start -0.12065 -0.305054)
			(end -0.12065 -0.2794)
			(stroke
				(width 0.1)
				(type default)
			)
			(layer "F.Fab")
		)
		(fp_line
			(start -0.12065 -0.2794)
			(end 0.12065 -0.2794)
			(stroke
				(width 0.1)
				(type default)
			)
			(layer "F.Fab")
		)
		(fp_line
			(start -0.12065 0.2794)
			(end -0.12065 0.3048)
			(stroke
				(width 0.1)
				(type default)
			)
			(layer "F.Fab")
		)
		(fp_line
			(start -0.12065 0.3048)
			(end -0.67945 0.3048)
			(stroke
				(width 0.1)
				(type default)
			)
			(layer "F.Fab")
		)
		(fp_line
			(start 0.120396 0.2794)
			(end -0.12065 0.2794)
			(stroke
				(width 0.1)
				(type default)
			)
			(layer "F.Fab")
		)
		(fp_line
			(start 0.120396 0.3048)
			(end 0.120396 0.2794)
			(stroke
				(width 0.1)
				(type default)
			)
			(layer "F.Fab")
		)
		(fp_line
			(start 0.12065 -0.3048)
			(end 0.67945 -0.3048)
			(stroke
				(width 0.1)
				(type default)
			)
			(layer "F.Fab")
		)
		(fp_line
			(start 0.12065 -0.2794)
			(end 0.12065 -0.3048)
			(stroke
				(width 0.1)
				(type default)
			)
			(layer "F.Fab")
		)
		(fp_line
			(start 0.67945 -0.3048)
			(end 0.67945 0.3048)
			(stroke
				(width 0.1)
				(type default)
			)
			(layer "F.Fab")
		)
		(fp_line
			(start 0.67945 0.3048)
			(end 0.120396 0.3048)
			(stroke
				(width 0.1)
				(type default)
			)
			(layer "F.Fab")
		)
		(pad "1" smd circle
			(at -0.40005 0)
			(size 0 0)
			(layers "F.Cu" "F.Mask" "F.Paste")
			(net "P1V05_PCH_AUX")
		)
		(pad "2" smd circle
			(at 0.40005 0)
			(size 0 0)
			(layers "F.Cu" "F.Mask" "F.Paste")
			(net "H_THERMTRIP_LVC1_N")
		)
	)
)
